# T6G (Grand Teton) — schematic netlist excerpt (pin names and nets, part order shuffled) for the footprints in the layout excerpt that follows; sources: Cadence DE-HDL packaged netlist, KiCad conversion of 04192023_DAF0TMB3IC0_F0TG_MB_C_brd_V02_OCP.brd

R1714  Q_RES  0 5% CHIP  pkg 0402LF  page 262 : A = SMB_SML1_PMBUS_HSC_SDA ; B = SMB_SML1_PMBUS_HSC_R_SDA
PR277  Q_RES  2.2 1% CHIP  pkg 0402LF  page 222 : A = PVDDCR_CPU1_P1_PVCC ; B = PVDDIO_P1_VCC1

(kicad_pcb
	(version 20260206)
	(generator "pcbnew")
	(generator_version "10.0")
	(general
		(thickness 1.6)
		(legacy_teardrops no)
	)
	(paper "A4")
	(title_block
		(title "04192023_DAF0TMB3IC0_F0TG_MB_C_brd_V02_OCP.brd")
		(comment 1 "Grand Teton / footprints 6015-6016 of 8354")
	)
	(layers
		(0 "F.Cu" signal "TOP")
		(4 "In1.Cu" signal "GND")
		(6 "In2.Cu" signal "IN1")
		(8 "In3.Cu" signal "GND1")
		(10 "In4.Cu" signal "IN2")
		(12 "In5.Cu" signal "GND2")
		(14 "In6.Cu" signal "IN3")
		(16 "In7.Cu" signal "GND3")
		(18 "In8.Cu" signal "VCC")
		(20 "In9.Cu" signal "VCC1")
		(22 "In10.Cu" signal "GND4")
		(24 "In11.Cu" signal "IN4")
		(26 "In12.Cu" signal "GND5")
		(28 "In13.Cu" signal "IN5")
		(30 "In14.Cu" signal "GND6")
		(32 "In15.Cu" signal "IN6")
		(34 "In16.Cu" signal "GND7")
		(2 "B.Cu" signal "BOTTOM")
		(9 "F.Adhes" user "F.Adhesive")
		(11 "B.Adhes" user "B.Adhesive")
		(13 "F.Paste" user "Package Geometry/Pastemask Top")
		(15 "B.Paste" user "Package Geometry/Pastemask Bottom")
		(5 "F.SilkS" user "Ref Des/Silkscreen Top")
		(7 "B.SilkS" user "Ref Des/Silkscreen Bottom")
		(1 "F.Mask" user "Board Geometry/Soldermask Top")
		(3 "B.Mask" user "Board Geometry/Soldermask Bottom")
		(17 "Dwgs.User" user "User.Drawings")
		(19 "Cmts.User" user "User.Comments")
		(21 "Eco1.User" user "User.Eco1")
		(23 "Eco2.User" user "User.Eco2")
		(25 "Edge.Cuts" user "Board Geometry/Outline")
		(27 "Margin" user)
		(31 "F.CrtYd" user "Package Geometry/Place Bound Top")
		(29 "B.CrtYd" user "Package Geometry/Place Bound Bottom")
		(35 "F.Fab" user "Ref Des/Assembly Top")
		(33 "B.Fab" user "Ref Des/Assembly Bottom")
	)
	(footprint ""
		(layer "B.Cu")
		(at 51.232562 -347.780356 -90)
		(property "Reference" "PR277"
			(at 0 0 90)
			(layer "B.SilkS")
			(hide yes)
			(effects
				(font
					(size 1.27 1.27)
				)
				(justify mirror)
			)
		)
		(property "Value" ""
			(at 0 0 90)
			(layer "B.Fab")
			(effects
				(font
					(size 1.27 1.27)
				)
				(justify mirror)
			)
		)
		(duplicate_pad_numbers_are_jumpers no)
		(fp_line
			(start -0.7874 0.4064)
			(end 0.7874 0.4064)
			(stroke
				(width 0.1524)
				(type default)
			)
			(layer "B.SilkS")
		)
		(fp_line
			(start 0.7874 0.4064)
			(end 0.7874 -0.4064)
			(stroke
				(width 0.1524)
				(type default)
			)
			(layer "B.SilkS")
		)
		(fp_line
			(start -0.7874 -0.4064)
			(end -0.7874 0.4064)
			(stroke
				(width 0.1524)
				(type default)
			)
			(layer "B.SilkS")
		)
		(fp_line
			(start 0.7874 -0.4064)
			(end -0.7874 -0.4064)
			(stroke
				(width 0.1524)
				(type default)
			)
			(layer "B.SilkS")
		)
		(fp_line
			(start -0.67945 0.3048)
			(end -0.120396 0.3048)
			(stroke
				(width 0.1)
				(type default)
			)
			(layer "B.Fab")
		)
		(fp_line
			(start -0.120396 0.3048)
			(end -0.120396 0.2794)
			(stroke
				(width 0.1)
				(type default)
			)
			(layer "B.Fab")
		)
		(fp_line
			(start 0.12065 0.3048)
			(end 0.67945 0.3048)
			(stroke
				(width 0.1)
				(type default)
			)
			(layer "B.Fab")
		)
		(fp_line
			(start 0.67945 0.3048)
			(end 0.67945 -0.305054)
			(stroke
				(width 0.1)
				(type default)
			)
			(layer "B.Fab")
		)
		(fp_line
			(start -0.120396 0.2794)
			(end 0.12065 0.2794)
			(stroke
				(width 0.1)
				(type default)
			)
			(layer "B.Fab")
		)
		(fp_line
			(start 0.12065 0.2794)
			(end 0.12065 0.3048)
			(stroke
				(width 0.1)
				(type default)
			)
			(layer "B.Fab")
		)
		(fp_line
			(start -0.12065 -0.2794)
			(end -0.12065 -0.3048)
			(stroke
				(width 0.1)
				(type default)
			)
			(layer "B.Fab")
		)
		(fp_line
			(start 0.12065 -0.2794)
			(end -0.12065 -0.2794)
			(stroke
				(width 0.1)
				(type default)
			)
			(layer "B.Fab")
		)
		(fp_line
			(start -0.67945 -0.3048)
			(end -0.67945 0.3048)
			(stroke
				(width 0.1)
				(type default)
			)
			(layer "B.Fab")
		)
		(fp_line
			(start -0.12065 -0.3048)
			(end -0.67945 -0.3048)
			(stroke
				(width 0.1)
				(type default)
			)
			(layer "B.Fab")
		)
		(fp_line
			(start 0.12065 -0.305054)
			(end 0.12065 -0.2794)
			(stroke
				(width 0.1)
				(type default)
			)
			(layer "B.Fab")
		)
		(fp_line
			(start 0.67945 -0.305054)
			(end 0.12065 -0.305054)
			(stroke
				(width 0.1)
				(type default)
			)
			(layer "B.Fab")
		)
		(pad "1" smd circle
			(at 0.40005 0 90)
			(size 0 0)
			(layers "B.Cu" "B.Mask" "B.Paste")
			(net "PVDDCR_CPU1_P1_PVCC")
		)
		(pad "2" smd circle
			(at -0.40005 0 90)
			(size 0 0)
			(layers "B.Cu" "B.Mask" "B.Paste")
			(net "PVDDIO_P1_VCC1")
		)
	)
	(footprint ""
		(layer "B.Cu")
		(at 181.37886 -406.918922 90)
		(property "Reference" "R1714"
			(at 0 0 90)
			(layer "B.SilkS")
			(hide yes)
			(effects
				(font
					(size 1.27 1.27)
				)
				(justify mirror)
			)
		)
		(property "Value" ""
			(at 0 0 90)
			(layer "B.Fab")
			(effects
				(font
					(size 1.27 1.27)
				)
				(justify mirror)
			)
		)
		(duplicate_pad_numbers_are_jumpers no)
		(fp_line
			(start 0.7874 -0.4064)
			(end -0.7874 -0.4064)
			(stroke
				(width 0.1524)
				(type default)
			)
			(layer "B.SilkS")
		)
		(fp_line
			(start -0.7874 -0.4064)
			(end -0.7874 0.4064)
			(stroke
				(width 0.1524)
				(type default)
			)
			(layer "B.SilkS")
		)
		(fp_line
			(start 0.7874 0.4064)
			(end 0.7874 -0.4064)
			(stroke
				(width 0.1524)
				(type default)
			)
			(layer "B.SilkS")
		)
		(fp_line
			(start -0.7874 0.4064)
			(end 0.7874 0.4064)
			(stroke
				(width 0.1524)
				(type default)
			)
			(layer "B.SilkS")
		)
		(fp_line
			(start 0.67945 -0.305054)
			(end 0.12065 -0.305054)
			(stroke
				(width 0.1)
				(type default)
			)
			(layer "B.Fab")
		)
		(fp_line
			(start 0.12065 -0.305054)
			(end 0.12065 -0.2794)
			(stroke
				(width 0.1)
				(type default)
			)
			(layer "B.Fab")
		)
		(fp_line
			(start -0.12065 -0.3048)
			(end -0.67945 -0.3048)
			(stroke
				(width 0.1)
				(type default)
			)
			(layer "B.Fab")
		)
		(fp_line
			(start -0.67945 -0.3048)
			(end -0.67945 0.3048)
			(stroke
				(width 0.1)
				(type default)
			)
			(layer "B.Fab")
		)
		(fp_line
			(start 0.12065 -0.2794)
			(end -0.12065 -0.2794)
			(stroke
				(width 0.1)
				(type default)
			)
			(layer "B.Fab")
		)
		(fp_line
			(start -0.12065 -0.2794)
			(end -0.12065 -0.3048)
			(stroke
				(width 0.1)
				(type default)
			)
			(layer "B.Fab")
		)
		(fp_line
			(start 0.12065 0.2794)
			(end 0.12065 0.3048)
			(stroke
				(width 0.1)
				(type default)
			)
			(layer "B.Fab")
		)
		(fp_line
			(start -0.120396 0.2794)
			(end 0.12065 0.2794)
			(stroke
				(width 0.1)
				(type default)
			)
			(layer "B.Fab")
		)
		(fp_line
			(start 0.67945 0.3048)
			(end 0.67945 -0.305054)
			(stroke
				(width 0.1)
				(type default)
			)
			(layer "B.Fab")
		)
		(fp_line
			(start 0.12065 0.3048)
			(end 0.67945 0.3048)
			(stroke
				(width 0.1)
				(type default)
			)
			(layer "B.Fab")
		)
		(fp_line
			(start -0.120396 0.3048)
			(end -0.120396 0.2794)
			(stroke
				(width 0.1)
				(type default)
			)
			(layer "B.Fab")
		)
		(fp_line
			(start -0.67945 0.3048)
			(end -0.120396 0.3048)
			(stroke
				(width 0.1)
				(type default)
			)
			(layer "B.Fab")
		)
		(pad "1" smd circle
			(at 0.40005 0 270)
			(size 0 0)
			(layers "B.Cu" "B.Mask" "B.Paste")
			(net "SMB_SML1_PMBUS_HSC_SDA")
		)
		(pad "2" smd circle
			(at -0.40005 0 270)
			(size 0 0)
			(layers "B.Cu" "B.Mask" "B.Paste")
			(net "SMB_SML1_PMBUS_HSC_R_SDA")
		)
	)
)
